(kicad_pcb
	(version 20241229)
	(generator "pcbnew")
	(generator_version "9.0")
	(general
		(thickness 1.711)
		(legacy_teardrops no)
	)
	(paper "A4")
	(title_block
		(title "Antmicro Baseboard for Jetson AGX Thor")
		(date "2026-02-18")
		(rev "1.1.0")
		(company "Antmicro Ltd")
		(comment 1 "www.antmicro.com")
		(comment 9 "footprints 124-128 of 1170")
	)
	(layers
		(0 "F.Cu" signal)
		(4 "In1.Cu" signal)
		(6 "In2.Cu" signal)
		(8 "In3.Cu" signal)
		(10 "In4.Cu" jumper)
		(12 "In5.Cu" signal)
		(14 "In6.Cu" signal)
		(16 "In7.Cu" signal)
		(18 "In8.Cu" signal)
		(2 "B.Cu" signal)
		(9 "F.Adhes" user "F.Adhesive")
		(11 "B.Adhes" user "B.Adhesive")
		(13 "F.Paste" user)
		(15 "B.Paste" user)
		(5 "F.SilkS" user "F.Silkscreen")
		(7 "B.SilkS" user "B.Silkscreen")
		(1 "F.Mask" user)
		(3 "B.Mask" user)
		(17 "Dwgs.User" user "User.Drawings")
		(19 "Cmts.User" user "User.Comments")
		(21 "Eco1.User" user "User.Eco1")
		(23 "Eco2.User" user "User.Eco2")
		(25 "Edge.Cuts" user)
		(27 "Margin" user)
		(31 "F.CrtYd" user "F.Courtyard")
		(29 "B.CrtYd" user "B.Courtyard")
		(35 "F.Fab" user)
		(33 "B.Fab" user)
	)
	(footprint "antmicro-footprints:C_0805_2012Metric"
		(layer "F.Cu")
		(at 164.09 79.81 90)
		(descr "Capacitor SMD 0805")
		(tags "capacitor SMD 0805")
		(property "Reference" "C287"
			(at -4.68 0.51 90)
			(layer "F.SilkS")
			(effects
				(font
					(size 0.7 0.7)
					(thickness 0.15)
				)
				(justify left bottom)
			)
		)
		(property "Value" "C_22u_25V_0805"
			(at -2.055717 1.963152 90)
			(layer "F.Fab")
			(effects
				(font
					(size 0.7 0.7)
					(thickness 0.15)
				)
				(justify left bottom)
			)
		)
		(property "Datasheet" "https://product.samsungsem.com/mlcc/CL21A226MAYNNN.do"
			(at 0 0 90)
			(layer "F.Fab")
			(hide yes)
			(effects
				(font
					(size 1.27 1.27)
					(thickness 0.15)
				)
			)
		)
		(property "Description" "SMT Multilayer Ceramic Capacitor, 22uF, +/-20%, 25V, X5R, 0805 [2012 Metric]"
			(at 0 0 90)
			(layer "F.Fab")
			(hide yes)
			(effects
				(font
					(size 1.27 1.27)
					(thickness 0.15)
				)
			)
		)
		(property "MPN" "CL21A226MAYNNNE"
			(at 0 0 90)
			(unlocked yes)
			(layer "F.Fab")
			(hide yes)
			(effects
				(font
					(size 1 1)
					(thickness 0.15)
				)
			)
		)
		(property "Manufacturer" "Samsung Electro-Mechanics"
			(at 0 0 90)
			(unlocked yes)
			(layer "F.Fab")
			(hide yes)
			(effects
				(font
					(size 1 1)
					(thickness 0.15)
				)
			)
		)
		(property "License" "Apache-2.0"
			(at 0 0 90)
			(unlocked yes)
			(layer "F.Fab")
			(hide yes)
			(effects
				(font
					(size 1 1)
					(thickness 0.15)
				)
			)
		)
		(property "Author" "Antmicro"
			(at 0 0 90)
			(unlocked yes)
			(layer "F.Fab")
			(hide yes)
			(effects
				(font
					(size 1 1)
					(thickness 0.15)
				)
			)
		)
		(property "Val" "22u"
			(at 0 0 90)
			(unlocked yes)
			(layer "F.Fab")
			(hide yes)
			(effects
				(font
					(size 1 1)
					(thickness 0.15)
				)
			)
		)
		(property "Voltage" "25V"
			(at 0 0 90)
			(unlocked yes)
			(layer "F.Fab")
			(hide yes)
			(effects
				(font
					(size 1 1)
					(thickness 0.15)
				)
			)
		)
		(property "Dielectric" "X5R"
			(at 0 0 90)
			(unlocked yes)
			(layer "F.Fab")
			(hide yes)
			(effects
				(font
					(size 1 1)
					(thickness 0.15)
				)
			)
		)
		(property "Public" "False"
			(at 0 0 90)
			(unlocked yes)
			(layer "F.Fab")
			(hide yes)
			(effects
				(font
					(size 1 1)
					(thickness 0.15)
				)
			)
		)
		(component_classes
			(class "DCDC_20V")
		)
		(sheetname "/DCDC/")
		(sheetfile "dcdc.kicad_sch")
		(attr smd)
		(fp_line
			(start -0.3 -0.7)
			(end 0.3 -0.7)
			(stroke
				(width 0.15)
				(type solid)
			)
			(layer "F.SilkS")
		)
		(fp_line
			(start -0.3 0.7)
			(end 0.3 0.7)
			(stroke
				(width 0.15)
				(type solid)
			)
			(layer "F.SilkS")
		)
		(fp_rect
			(start 1.95 -0.9)
			(end -1.95 0.9)
			(stroke
				(width 0.05)
				(type default)
			)
			(fill no)
			(layer "F.CrtYd")
		)
		(fp_rect
			(start -0.95 -0.675)
			(end 0.95 0.675)
			(stroke
				(width 0.15)
				(type solid)
			)
			(fill no)
			(layer "F.Fab")
		)
		(fp_text user "Author: Antmicro"
			(at -1.9 5.947 90)
			(layer "F.Fab")
			(effects
				(font
					(size 0.7 0.7)
					(thickness 0.15)
				)
				(justify left bottom)
			)
		)
		(fp_text user "${REFERENCE}"
			(at -1.9 3.947 90)
			(layer "F.Fab")
			(effects
				(font
					(size 0.7 0.7)
					(thickness 0.15)
				)
				(justify left bottom)
			)
		)
		(fp_text user "License: Apache-2.0"
			(at -1.9 4.947 90)
			(layer "F.Fab")
			(effects
				(font
					(size 0.7 0.7)
					(thickness 0.15)
				)
				(justify left bottom)
			)
		)
		(pad "1" smd roundrect
			(at -1.1 0 90)
			(size 1.2 1.3)
			(layers "F.Cu" "F.Mask" "F.Paste")
			(roundrect_rratio 0.25)
			(net 1 "GND")
			(pintype "passive")
		)
		(pad "2" smd roundrect
			(at 1.1 0 90)
			(size 1.2 1.3)
			(layers "F.Cu" "F.Mask" "F.Paste")
			(roundrect_rratio 0.25)
			(net 1105 "/DCDC/20V_OUT")
			(pintype "passive")
		)
	)
	(footprint "antmicro-footprints:TP_SMD_0.75mm"
		(layer "F.Cu")
		(at 184.25 57.14 90)
		(property "Reference" "TP4"
			(at -1.51 -0.69 90)
			(layer "F.SilkS")
			(hide yes)
			(effects
				(font
					(size 0.7 0.7)
					(thickness 0.15)
				)
				(justify left bottom)
			)
		)
		(property "Value" "TP_0.75mm_SMD"
			(at 0 1.2 90)
			(layer "F.Fab")
			(effects
				(font
					(size 0.7 0.7)
					(thickness 0.15)
				)
				(justify left bottom)
			)
		)
		(property "Description" "SMT test point"
			(at 0 0 90)
			(layer "F.Fab")
			(hide yes)
			(effects
				(font
					(size 1.27 1.27)
					(thickness 0.15)
				)
			)
		)
		(property "MPN" ""
			(at 0 0 90)
			(unlocked yes)
			(layer "F.Fab")
			(hide yes)
			(effects
				(font
					(size 1 1)
					(thickness 0.15)
				)
			)
		)
		(property "Manufacturer" ""
			(at 0 0 90)
			(unlocked yes)
			(layer "F.Fab")
			(hide yes)
			(effects
				(font
					(size 1 1)
					(thickness 0.15)
				)
			)
		)
		(property "Author" "Antmicro"
			(at 0 0 90)
			(unlocked yes)
			(layer "F.Fab")
			(hide yes)
			(effects
				(font
					(size 1 1)
					(thickness 0.15)
				)
			)
		)
		(property "License" "Apache-2.0"
			(at 0 0 90)
			(unlocked yes)
			(layer "F.Fab")
			(hide yes)
			(effects
				(font
					(size 1 1)
					(thickness 0.15)
				)
			)
		)
		(sheetname "/Power/")
		(sheetfile "power.kicad_sch")
		(attr exclude_from_pos_files exclude_from_bom)
		(fp_circle
			(center 0 0)
			(end 0.475 0)
			(stroke
				(width 0.05)
				(type default)
			)
			(fill no)
			(layer "F.CrtYd")
		)
		(fp_text user "Author: Antmicro"
			(at -0.4 3.901 90)
			(layer "F.Fab")
			(effects
				(font
					(size 0.7 0.7)
					(thickness 0.15)
				)
				(justify left bottom)
			)
		)
		(fp_text user "License: Apache-2.0"
			(at -0.4 5.101 90)
			(layer "F.Fab")
			(effects
				(font
					(size 0.7 0.7)
					(thickness 0.15)
				)
				(justify left bottom)
			)
		)
		(fp_text user "${REFERENCE}"
			(at -0.4 2.7 90)
			(layer "F.Fab")
			(effects
				(font
					(size 0.7 0.7)
					(thickness 0.15)
				)
				(justify left bottom)
			)
		)
		(pad "1" smd circle
			(at 0 0 90)
			(size 0.75 0.75)
			(layers "F.Cu" "F.Mask")
			(net 13 "VCC")
			(pinfunction "1")
			(pintype "passive")
		)
	)
	(footprint "antmicro-footprints:C_0402_1005Metric"
		(layer "F.Cu")
		(at 65.68 85.87 90)
		(descr "Capacitor SMD 0402")
		(tags "capacitor SMD 0402")
		(property "Reference" "C156"
			(at 0.87 0.32 90)
			(layer "F.SilkS")
			(effects
				(font
					(size 0.7 0.7)
					(thickness 0.15)
				)
				(justify left bottom)
			)
		)
		(property "Value" "C_100n_0402"
			(at -1.022927 2.155213 90)
			(layer "F.Fab")
			(effects
				(font
					(size 0.7 0.7)
					(thickness 0.15)
				)
				(justify left bottom)
			)
		)
		(property "Datasheet" "https://www.murata.com/products/productdetail?partno=GRM155R61H104KE14%23"
			(at 0 0 90)
			(layer "F.Fab")
			(hide yes)
			(effects
				(font
					(size 1.27 1.27)
					(thickness 0.15)
				)
			)
		)
		(property "Description" "SMD Multilayer Ceramic Capacitor, 0.1 µF, 50 V, 0402 [1005 Metric], ± 10%, X5R, GRM Series"
			(at 0 0 90)
			(layer "F.Fab")
			(hide yes)
			(effects
				(font
					(size 1.27 1.27)
					(thickness 0.15)
				)
			)
		)
		(property "Manufacturer" "Murata"
			(at 0 0 90)
			(unlocked yes)
			(layer "F.Fab")
			(hide yes)
			(effects
				(font
					(size 1 1)
					(thickness 0.15)
				)
			)
		)
		(property "MPN" "GRM155R61H104KE14D"
			(at 0 0 90)
			(unlocked yes)
			(layer "F.Fab")
			(hide yes)
			(effects
				(font
					(size 1 1)
					(thickness 0.15)
				)
			)
		)
		(property "Val" "100n"
			(at 0 0 90)
			(unlocked yes)
			(layer "F.Fab")
			(hide yes)
			(effects
				(font
					(size 1 1)
					(thickness 0.15)
				)
			)
		)
		(property "License" "Apache-2.0"
			(at 0 0 90)
			(unlocked yes)
			(layer "F.Fab")
			(hide yes)
			(effects
				(font
					(size 1 1)
					(thickness 0.15)
				)
			)
		)
		(property "Author" "Antmicro"
			(at 0 0 90)
			(unlocked yes)
			(layer "F.Fab")
			(hide yes)
			(effects
				(font
					(size 1 1)
					(thickness 0.15)
				)
			)
		)
		(property "Voltage" "50V"
			(at 0 0 90)
			(unlocked yes)
			(layer "F.Fab")
			(hide yes)
			(effects
				(font
					(size 1 1)
					(thickness 0.15)
				)
			)
		)
		(property "Dielectric" "X5R"
			(at 0 0 90)
			(unlocked yes)
			(layer "F.Fab")
			(hide yes)
			(effects
				(font
					(size 1 1)
					(thickness 0.15)
				)
			)
		)
		(sheetname "/CSI/")
		(sheetfile "csi.kicad_sch")
		(attr smd)
		(fp_rect
			(start -0.925 -0.47)
			(end 0.925 0.47)
			(stroke
				(width 0.05)
				(type default)
			)
			(fill no)
			(layer "F.CrtYd")
		)
		(fp_line
			(start 0.504 -0.25)
			(end 0.504 0.248)
			(stroke
				(width 0.15)
				(type solid)
			)
			(layer "F.Fab")
		)
		(fp_line
			(start -0.494 -0.25)
			(end 0.504 -0.25)
			(stroke
				(width 0.15)
				(type solid)
			)
			(layer "F.Fab")
		)
		(fp_line
			(start 0.504 0.248)
			(end -0.494 0.248)
			(stroke
				(width 0.15)
				(type solid)
			)
			(layer "F.Fab")
		)
		(fp_line
			(start -0.494 0.248)
			(end -0.494 -0.25)
			(stroke
				(width 0.15)
				(type solid)
			)
			(layer "F.Fab")
		)
		(fp_text user "Author: Antmicro"
			(at -0.939 3.399 90)
			(layer "F.Fab")
			(effects
				(font
					(size 0.7 0.7)
					(thickness 0.15)
				)
				(justify left bottom)
			)
		)
		(fp_text user "License: Apache-2.0"
			(at -0.939 5.799 90)
			(layer "F.Fab")
			(effects
				(font
					(size 0.7 0.7)
					(thickness 0.15)
				)
				(justify left bottom)
			)
		)
		(fp_text user "${REFERENCE}"
			(at -0.939 4.599 90)
			(layer "F.Fab")
			(effects
				(font
					(size 0.7 0.7)
					(thickness 0.15)
				)
				(justify left bottom)
			)
		)
		(pad "1" smd roundrect
			(at -0.48 0 90)
			(size 0.59 0.64)
			(layers "F.Cu" "F.Mask" "F.Paste")
			(roundrect_rratio 0.25)
			(net 5 "+5V")
			(pintype "passive")
		)
		(pad "2" smd roundrect
			(at 0.48 0 90)
			(size 0.59 0.64)
			(layers "F.Cu" "F.Mask" "F.Paste")
			(roundrect_rratio 0.25)
			(net 1 "GND")
			(pintype "passive")
		)
	)
	(footprint "antmicro-footprints:R_0402_1005Metric"
		(layer "F.Cu")
		(at 136 109.1 180)
		(descr "Resistor SMD 0402")
		(tags "resistor SMD 0402")
		(property "Reference" "R346"
			(at 1 0.3 0)
			(layer "F.SilkS")
			(effects
				(font
					(size 0.7 0.7)
					(thickness 0.15)
				)
				(justify right top)
			)
		)
		(property "Value" "R_0R_0402"
			(at -1.011843 1.772047 0)
			(layer "F.Fab")
			(effects
				(font
					(size 0.7 0.7)
					(thickness 0.15)
				)
				(justify right top)
			)
		)
		(property "Datasheet" "https://industrial.panasonic.com/cdbs/www-data/pdf/RDA0000/AOA0000C301.pdf"
			(at 0 0 0)
			(layer "F.Fab")
			(hide yes)
			(effects
				(font
					(size 1.27 1.27)
					(thickness 0.15)
				)
			)
		)
		(property "Description" "SMD Chip Resistor, Jumper, 0 ohm, 100 mW, 0402 [1005 Metric], Thick Film, General Purpose"
			(at 0 0 0)
			(layer "F.Fab")
			(hide yes)
			(effects
				(font
					(size 1.27 1.27)
					(thickness 0.15)
				)
			)
		)
		(property "MPN" "ERJ2GE0R00X"
			(at 0 0 180)
			(unlocked yes)
			(layer "F.Fab")
			(hide yes)
			(effects
				(font
					(size 1 1)
					(thickness 0.15)
				)
			)
		)
		(property "Manufacturer" "Panasonic"
			(at 0 0 180)
			(unlocked yes)
			(layer "F.Fab")
			(hide yes)
			(effects
				(font
					(size 1 1)
					(thickness 0.15)
				)
			)
		)
		(property "License" "Apache-2.0"
			(at 0 0 180)
			(unlocked yes)
			(layer "F.Fab")
			(hide yes)
			(effects
				(font
					(size 1 1)
					(thickness 0.15)
				)
			)
		)
		(property "Author" "Antmicro"
			(at 0 0 180)
			(unlocked yes)
			(layer "F.Fab")
			(hide yes)
			(effects
				(font
					(size 1 1)
					(thickness 0.15)
				)
			)
		)
		(property "Val" "0R"
			(at 0 0 180)
			(unlocked yes)
			(layer "F.Fab")
			(hide yes)
			(effects
				(font
					(size 1 1)
					(thickness 0.15)
				)
			)
		)
		(property "Tolerance" "~"
			(at 0 0 180)
			(unlocked yes)
			(layer "F.Fab")
			(hide yes)
			(effects
				(font
					(size 1 1)
					(thickness 0.15)
				)
			)
		)
		(property "Current" "1A"
			(at 0 0 180)
			(unlocked yes)
			(layer "F.Fab")
			(hide yes)
			(effects
				(font
					(size 1 1)
					(thickness 0.15)
				)
			)
		)
		(sheetname "/Peripherals/")
		(sheetfile "peripherals.kicad_sch")
		(attr smd)
		(fp_rect
			(start -0.925 -0.47)
			(end 0.925 0.47)
			(stroke
				(width 0.05)
				(type default)
			)
			(fill no)
			(layer "F.CrtYd")
		)
		(fp_rect
			(start -0.5 -0.25)
			(end 0.5 0.25)
			(stroke
				(width 0.15)
				(type solid)
			)
			(fill no)
			(layer "F.Fab")
		)
		(fp_text user "License: Apache-2.0"
			(at -0.95 5.169 0)
			(layer "F.Fab")
			(effects
				(font
					(size 0.7 0.7)
					(thickness 0.15)
				)
				(justify right top)
			)
		)
		(fp_text user "Author: Antmicro"
			(at -0.95 4.169 0)
			(layer "F.Fab")
			(effects
				(font
					(size 0.7 0.7)
					(thickness 0.15)
				)
				(justify right top)
			)
		)
		(fp_text user "${REFERENCE}"
			(at -0.95 3.168 0)
			(layer "F.Fab")
			(effects
				(font
					(size 0.7 0.7)
					(thickness 0.15)
				)
				(justify right top)
			)
		)
		(pad "1" smd roundrect
			(at -0.48 0 180)
			(size 0.59 0.64)
			(layers "F.Cu" "F.Mask" "F.Paste")
			(roundrect_rratio 0.25)
			(net 1314 "/Peripherals/GPIOEX_P0_1")
			(pintype "passive")
		)
		(pad "2" smd roundrect
			(at 0.48 0 180)
			(size 0.59 0.64)
			(layers "F.Cu" "F.Mask" "F.Paste")
			(roundrect_rratio 0.25)
			(net 123 "/CSI/CAM_CTRL.CSIB_PEN")
			(pintype "passive")
		)
	)
	(footprint "antmicro-footprints:R_0402_1005Metric"
		(layer "F.Cu")
		(at 92.98 148.205736)
		(descr "Resistor SMD 0402")
		(tags "resistor SMD 0402")
		(property "Reference" "R195"
			(at 1.02 0.394264 0)
			(layer "F.SilkS")
			(effects
				(font
					(size 0.7 0.7)
					(thickness 0.15)
				)
				(justify left bottom)
			)
		)
		(property "Value" "R_0R_0402"
			(at -1.011843 1.772046 0)
			(layer "F.Fab")
			(effects
				(font
					(size 0.7 0.7)
					(thickness 0.15)
				)
				(justify left bottom)
			)
		)
		(property "Datasheet" "https://industrial.panasonic.com/cdbs/www-data/pdf/RDA0000/AOA0000C301.pdf"
			(at 0 0 0)
			(layer "F.Fab")
			(hide yes)
			(effects
				(font
					(size 1.27 1.27)
					(thickness 0.15)
				)
			)
		)
		(property "Description" "SMD Chip Resistor, Jumper, 0 ohm, 100 mW, 0402 [1005 Metric], Thick Film, General Purpose"
			(at 0 0 0)
			(layer "F.Fab")
			(hide yes)
			(effects
				(font
					(size 1.27 1.27)
					(thickness 0.15)
				)
			)
		)
		(property "MPN" "ERJ2GE0R00X"
			(at 0 0 0)
			(unlocked yes)
			(layer "F.Fab")
			(hide yes)
			(effects
				(font
					(size 1 1)
					(thickness 0.15)
				)
			)
		)
		(property "Manufacturer" "Panasonic"
			(at 0 0 0)
			(unlocked yes)
			(layer "F.Fab")
			(hide yes)
			(effects
				(font
					(size 1 1)
					(thickness 0.15)
				)
			)
		)
		(property "License" "Apache-2.0"
			(at 0 0 0)
			(unlocked yes)
			(layer "F.Fab")
			(hide yes)
			(effects
				(font
					(size 1 1)
					(thickness 0.15)
				)
			)
		)
		(property "Author" "Antmicro"
			(at 0 0 0)
			(unlocked yes)
			(layer "F.Fab")
			(hide yes)
			(effects
				(font
					(size 1 1)
					(thickness 0.15)
				)
			)
		)
		(property "Val" "0R"
			(at 0 0 0)
			(unlocked yes)
			(layer "F.Fab")
			(hide yes)
			(effects
				(font
					(size 1 1)
					(thickness 0.15)
				)
			)
		)
		(property "Tolerance" "~"
			(at 0 0 0)
			(unlocked yes)
			(layer "F.Fab")
			(hide yes)
			(effects
				(font
					(size 1 1)
					(thickness 0.15)
				)
			)
		)
		(property "Current" "1A"
			(at 0 0 0)
			(unlocked yes)
			(layer "F.Fab")
			(hide yes)
			(effects
				(font
					(size 1 1)
					(thickness 0.15)
				)
			)
		)
		(sheetname "/SoM_IO2/")
		(sheetfile "som_io2.kicad_sch")
		(attr smd exclude_from_pos_files exclude_from_bom dnp)
		(fp_poly
			(pts
				(xy -0.925 -0.47) (xy -0.925 0.47) (xy 0.925 0.47) (xy 0.925 -0.47)
			)
			(stroke
				(width 0.05)
				(type default)
			)
			(fill no)
			(layer "F.CrtYd")
		)
		(fp_poly
			(pts
				(xy -0.5 -0.25) (xy -0.5 0.25) (xy 0.5 0.25) (xy 0.5 -0.25)
			)
			(stroke
				(width 0.15)
				(type solid)
			)
			(fill no)
			(layer "F.Fab")
		)
		(fp_text user "${REFERENCE}"
			(at -0.95 3.168 0)
			(layer "F.Fab")
			(effects
				(font
					(size 0.7 0.7)
					(thickness 0.15)
				)
				(justify left bottom)
			)
		)
		(fp_text user "Author: Antmicro"
			(at -0.95 4.169 0)
			(layer "F.Fab")
			(effects
				(font
					(size 0.7 0.7)
					(thickness 0.15)
				)
				(justify left bottom)
			)
		)
		(fp_text user "License: Apache-2.0"
			(at -0.949999 5.169 0)
			(layer "F.Fab")
			(effects
				(font
					(size 0.7 0.7)
					(thickness 0.15)
				)
				(justify left bottom)
			)
		)
		(pad "1" smd roundrect
			(at -0.48 0)
			(size 0.59 0.64)
			(layers "F.Cu" "F.Mask" "F.Paste")
			(roundrect_rratio 0.25)
			(net 1002 "/SoM_IO2/C2_REFCLK-")
			(pintype "passive")
		)
		(pad "2" smd roundrect
			(at 0.48 0)
			(size 0.59 0.64)
			(layers "F.Cu" "F.Mask" "F.Paste")
			(roundrect_rratio 0.25)
			(net 668 "/SoM_IO2/PCIe_{C2x1}R_CLK-")
			(pintype "passive")
		)
	)
)
